#ISCELL
  mstr_misc dns *
  *
#ISCELL
  pure_quanta quanta_title_block_c *
  *
#ISCELL
  pure_quanta_power universal_gnd *
  page197_i1
#ISCELL
  standard offpage *
  page197_i10
#ISCELL
  pure_quanta_power universal_gnd *
  page197_i11
#CELL
  pure_quanta q_cap *
  page197_i12
#CELL
  pure_quanta q_res *
  page197_i13
#ISCELL
  pure_quanta_power vcc_core *
  page197_i14
#ISCELL
  pure_quanta_power universal_gnd *
  page197_i15
#CELL
  pure_quanta q_cap *
  page197_i16
#ISCELL
  pure_quanta_power universal_gnd *
  page197_i17
#ISCELL
  pure_quanta_power universal_gnd *
  page197_i18
#CELL
  pure_quanta q_res *
  page197_i19
#ISCELL
  pure_quanta_power universal_gnd *
  page197_i2
#CELL
  pure_quanta q_cap *
  page197_i20
#CELL
  pure_quanta q_cap *
  page197_i21
#CELL
  pure_quanta q_res *
  page197_i22
#CELL
  pure_quanta q_cap *
  page197_i23
#ISCELL
  pure_quanta_power universal_gnd *
  page197_i24
#ISCELL
  pure_quanta_power universal_gnd *
  page197_i25
#CELL
  pure_quanta q_res *
  page197_i26
#ISCELL
  pure_quanta_power universal_gnd *
  page197_i27
#CELL
  pure_quanta q_res *
  page197_i28
#ISCELL
  standard offpage *
  page197_i29
#CELL
  pure_quanta q_cap *
  page197_i3
#ISCELL
  standard offpage *
  page197_i30
#ISCELL
  standard offpage *
  page197_i31
#ISCELL
  standard offpage *
  page197_i32
#ISCELL
  pure_quanta_power universal_gnd *
  page197_i33
#CELL
  pure_quanta q_cap *
  page197_i34
#CELL
  pure_quanta q_res *
  page197_i35
#ISCELL
  pure_quanta_power vcc_core *
  page197_i36
#ISCELL
  pure_quanta_power universal_gnd *
  page197_i37
#CELL
  pure_quanta q_cap *
  page197_i38
#CELL
  pure_quanta isl99390frztr5935 *
  page197_i39
#CELL
  pure_quanta q_cap *
  page197_i4
#CELL
  pure_quanta q_cap *
  page197_i40
#CELL
  pure_quanta q_cap *
  page197_i41
#CELL
  pure_quanta q_cap *
  page197_i42
#CELL
  pure_quanta q_res *
  page197_i43
#CELL
  pure_quanta q_cap *
  page197_i44
#CELL
  pure_quanta q_res *
  page197_i45
#ISCELL
  standard offpage *
  page197_i46
#CELL
  pure_quanta q_cap *
  page197_i47
#CELL
  pure_quanta q_cap *
  page197_i48
#CELL
  pure_quanta q_cap *
  page197_i49
#ISCELL
  pure_quanta_power universal_gnd *
  page197_i5
#CELL
  pure_quanta q_res *
  page197_i50
#ISCELL
  pure_quanta_power universal_gnd *
  page197_i51
#CELL
  pure_quanta q_cap *
  page197_i52
#ISCELL
  pure_quanta_power vcc_core *
  page197_i53
#ISCELL
  standard offpage *
  page197_i54
#CELL
  pure_quanta q_cap *
  page197_i55
#ISCELL
  pure_quanta_power universal_gnd *
  page197_i56
#CELL
  pure_quanta q_cap *
  page197_i57
#CELL
  pure_quanta q_capp *
  page197_i58
#CELL
  pure_quanta q_capp *
  page197_i59
#CELL
  pure_quanta q_res *
  page197_i6
#ISCELL
  pure_quanta_power vcc_core *
  page197_i60
#ISCELL
  pure_quanta_power universal_gnd *
  page197_i61
#CELL
  pure_quanta q_capp *
  page197_i62
#ISCELL
  pure_quanta_power vcc_core *
  page197_i63
#ISCELL
  standard offpage *
  page197_i64
#CELL
  pure_quanta q_cap *
  page197_i65
#CELL
  pure_quanta q_cap *
  page197_i66
#ISCELL
  pure_quanta_power universal_gnd *
  page197_i67
#ISCELL
  pure_quanta_power vcc_core *
  page197_i68
#CELL
  pure_quanta q_cap *
  page197_i69
#ISCELL
  standard offpage *
  page197_i7
#CELL
  pure_quanta q_inductor4p_14 *
  page197_i71
#CELL
  pure_quanta q_inductor *
  page197_i72
#ISCELL
  pure_quanta_power universal_gnd *
  page197_i73
#CELL
  pure_quanta q_cap *
  page197_i74
#ISCELL
  pure_quanta_power vcc_core *
  page197_i75
#ISCELL
  pure_quanta_power universal_gnd *
  page197_i76
#CELL
  pure_quanta q_cap *
  page197_i77
#CELL
  pure_quanta q_cap *
  page197_i78
#CELL
  pure_quanta q_cap *
  page197_i79
#ISCELL
  standard offpage *
  page197_i8
#ISCELL
  pure_quanta_power universal_gnd *
  page197_i80
#CELL
  pure_quanta q_res *
  page197_i81
#ISCELL
  pure_quanta_power vcc_core *
  page197_i82
#CELL
  pure_quanta q_inductor4p_14 *
  page197_i83
#CELL
  pure_quanta isl99390frztr5935 *
  page197_i84
#CELL
  pure_quanta q_capp *
  page197_i85
#CELL
  pure_quanta q_cap *
  page197_i86
#ISCELL
  standard offpage *
  page197_i9
